(kicad_pcb
	(version 20260206)
	(generator "pcbnew")
	(generator_version "10.0")
	(general
		(thickness 1.6)
		(legacy_teardrops no)
	)
	(paper "A4")
	(title_block
		(title "Wiwynn_Tioga_Pass_MB.brd")
		(comment 1 "Tioga Pass / footprints 4085-4092 of 4770")
	)
	(layers
		(0 "F.Cu" signal "TOP")
		(4 "In1.Cu" signal "L2GND")
		(6 "In2.Cu" signal "L3")
		(8 "In3.Cu" signal "L4GND")
		(10 "In4.Cu" signal "L5")
		(12 "In5.Cu" signal "L6GND")
		(14 "In6.Cu" signal "L7VCC")
		(16 "In7.Cu" signal "L8VCC")
		(18 "In8.Cu" signal "L9GND")
		(20 "In9.Cu" signal "L10")
		(22 "In10.Cu" signal "L11GND")
		(24 "In11.Cu" signal "L12")
		(26 "In12.Cu" signal "L13GND")
		(2 "B.Cu" signal "BOTTOM")
		(9 "F.Adhes" user "F.Adhesive")
		(11 "B.Adhes" user "B.Adhesive")
		(13 "F.Paste" user "Package Geometry/Pastemask Top")
		(15 "B.Paste" user "Package Geometry/Pastemask Bottom")
		(5 "F.SilkS" user "Ref Des/Silkscreen Top")
		(7 "B.SilkS" user "Ref Des/Silkscreen Bottom")
		(1 "F.Mask" user "Board Geometry/Soldermask Top")
		(3 "B.Mask" user "Board Geometry/Soldermask Bottom")
		(17 "Dwgs.User" user "User.Drawings")
		(19 "Cmts.User" user "User.Comments")
		(21 "Eco1.User" user "User.Eco1")
		(23 "Eco2.User" user "User.Eco2")
		(25 "Edge.Cuts" user "Board Geometry/Outline")
		(27 "Margin" user)
		(31 "F.CrtYd" user "Package Geometry/Place Bound Top")
		(29 "B.CrtYd" user "Package Geometry/Place Bound Bottom")
		(35 "F.Fab" user "Ref Des/Assembly Top")
		(33 "B.Fab" user "Ref Des/Assembly Bottom")
	)
	(footprint ""
		(layer "B.Cu")
		(at 471.14206 -130.0734)
		(property "Reference" "C1M29"
			(at 0 0 0)
			(layer "B.SilkS")
			(hide yes)
			(effects
				(font
					(size 1.27 1.27)
				)
				(justify mirror)
			)
		)
		(property "Value" ""
			(at 0 0 0)
			(layer "B.Fab")
			(effects
				(font
					(size 1.27 1.27)
				)
				(justify mirror)
			)
		)
		(duplicate_pad_numbers_are_jumpers no)
		(fp_poly
			(pts
				(xy -0.3048 -0.1016) (xy -0.3048 0.9906) (xy 0.3048 0.9906) (xy 0.3048 -0.1016)
			)
			(stroke
				(width 0)
				(type default)
			)
			(fill no)
			(layer "B.CrtYd")
		)
		(fp_line
			(start -0.3048 -0.1016)
			(end 0.3048 -0.1016)
			(stroke
				(width 0.1)
				(type default)
			)
			(layer "B.Fab")
		)
		(fp_line
			(start -0.3048 0.9906)
			(end -0.3048 -0.1016)
			(stroke
				(width 0.1)
				(type default)
			)
			(layer "B.Fab")
		)
		(fp_line
			(start 0.3048 -0.1016)
			(end 0.3048 0.9906)
			(stroke
				(width 0.1)
				(type default)
			)
			(layer "B.Fab")
		)
		(fp_line
			(start 0.3048 0.9906)
			(end -0.3048 0.9906)
			(stroke
				(width 0.1)
				(type default)
			)
			(layer "B.Fab")
		)
		(pad "1" smd rect
			(at 0 0 180)
			(size 0.508 0.508)
			(layers "B.Cu" "B.Mask" "B.Paste")
			(net "P1V8_MCP_CPU0")
		)
		(pad "2" smd rect
			(at 0 0.889 180)
			(size 0.508 0.508)
			(layers "B.Cu" "B.Mask" "B.Paste")
			(net "GND")
		)
		(zone
			(layer "B.Cu")
			(hatch none 0.5)
			(connect_pads
				(clearance 0)
			)
			(min_thickness 0.25)
			(keepout
				(tracks allowed)
				(vias not_allowed)
				(pads allowed)
				(copperpour not_allowed)
				(footprints allowed)
			)
			(placement
				(enabled no)
				(sheetname "")
			)
			(fill
				(thermal_gap 0.5)
				(thermal_bridge_width 0.5)
				(island_removal_mode 0)
			)
			(polygon
				(pts
					(xy 471.39606 -129.8194) (xy 470.88806 -129.8194) (xy 470.88806 -129.4384) (xy 471.39606 -129.4384)
				)
			)
		)
		(zone
			(layer "B.Cu")
			(hatch none 0.5)
			(connect_pads
				(clearance 0)
			)
			(min_thickness 0.25)
			(keepout
				(tracks not_allowed)
				(vias allowed)
				(pads allowed)
				(copperpour not_allowed)
				(footprints allowed)
			)
			(placement
				(enabled no)
				(sheetname "")
			)
			(fill
				(thermal_gap 0.5)
				(thermal_bridge_width 0.5)
				(island_removal_mode 0)
			)
			(polygon
				(pts
					(xy 471.39606 -129.4384) (xy 470.88806 -129.4384) (xy 470.88806 -129.8194) (xy 471.39606 -129.8194)
				)
			)
		)
	)
	(footprint ""
		(layer "B.Cu")
		(at 31.0134 -80.4926 180)
		(property "Reference" "CT19"
			(at 0.8382 -0.84963 180)
			(unlocked yes)
			(layer "B.SilkS")
			(effects
				(font
					(size 0.7874 0.5842)
					(thickness 0.1524)
				)
				(justify left mirror)
			)
		)
		(property "Value" ""
			(at 0 0 0)
			(layer "B.Fab")
			(effects
				(font
					(size 1.27 1.27)
				)
				(justify mirror)
			)
		)
		(duplicate_pad_numbers_are_jumpers no)
		(fp_poly
			(pts
				(xy -0.3048 -0.1016) (xy -0.3048 0.9906) (xy 0.3048 0.9906) (xy 0.3048 -0.1016)
			)
			(stroke
				(width 0)
				(type default)
			)
			(fill no)
			(layer "B.CrtYd")
		)
		(fp_line
			(start 0.3048 0.9906)
			(end -0.3048 0.9906)
			(stroke
				(width 0.1)
				(type default)
			)
			(layer "B.Fab")
		)
		(fp_line
			(start 0.3048 -0.1016)
			(end 0.3048 0.9906)
			(stroke
				(width 0.1)
				(type default)
			)
			(layer "B.Fab")
		)
		(fp_line
			(start -0.3048 0.9906)
			(end -0.3048 -0.1016)
			(stroke
				(width 0.1)
				(type default)
			)
			(layer "B.Fab")
		)
		(fp_line
			(start -0.3048 -0.1016)
			(end 0.3048 -0.1016)
			(stroke
				(width 0.1)
				(type default)
			)
			(layer "B.Fab")
		)
		(pad "1" smd rect
			(at 0 0)
			(size 0.508 0.508)
			(layers "B.Cu" "B.Mask" "B.Paste")
			(net "A_TSENSE_PVCCIN_CPU1")
		)
		(pad "2" smd rect
			(at 0 0.889)
			(size 0.508 0.508)
			(layers "B.Cu" "B.Mask" "B.Paste")
			(net "GND")
		)
		(zone
			(layer "B.Cu")
			(hatch none 0.5)
			(connect_pads
				(clearance 0)
			)
			(min_thickness 0.25)
			(keepout
				(tracks not_allowed)
				(vias allowed)
				(pads allowed)
				(copperpour not_allowed)
				(footprints allowed)
			)
			(placement
				(enabled no)
				(sheetname "")
			)
			(fill
				(thermal_gap 0.5)
				(thermal_bridge_width 0.5)
				(island_removal_mode 0)
			)
			(polygon
				(pts
					(xy 30.7594 -81.1276) (xy 31.2674 -81.1276) (xy 31.2674 -80.7466) (xy 30.7594 -80.7466)
				)
			)
		)
		(zone
			(layer "B.Cu")
			(hatch none 0.5)
			(connect_pads
				(clearance 0)
			)
			(min_thickness 0.25)
			(keepout
				(tracks allowed)
				(vias not_allowed)
				(pads allowed)
				(copperpour not_allowed)
				(footprints allowed)
			)
			(placement
				(enabled no)
				(sheetname "")
			)
			(fill
				(thermal_gap 0.5)
				(thermal_bridge_width 0.5)
				(island_removal_mode 0)
			)
			(polygon
				(pts
					(xy 30.7594 -80.7466) (xy 31.2674 -80.7466) (xy 31.2674 -81.1276) (xy 30.7594 -81.1276)
				)
			)
		)
	)
	(footprint ""
		(layer "B.Cu")
		(at 401.599146 -35.569652 90)
		(property "Reference" "R25W107"
			(at 0.8382 -0.67818 90)
			(unlocked yes)
			(layer "B.SilkS")
			(effects
				(font
					(size 0.4064 0.254)
					(thickness 0.1524)
				)
				(justify left mirror)
			)
		)
		(property "Value" ""
			(at 0 0 90)
			(layer "B.Fab")
			(effects
				(font
					(size 1.27 1.27)
				)
				(justify mirror)
			)
		)
		(duplicate_pad_numbers_are_jumpers no)
		(fp_poly
			(pts
				(xy 0.2794 -0.1016) (xy -0.2794 -0.1016) (xy -0.2794 0.9906) (xy 0.2794 0.9906)
			)
			(stroke
				(width 0)
				(type default)
			)
			(fill no)
			(layer "B.CrtYd")
		)
		(fp_line
			(start 0.2794 -0.1016)
			(end 0.2794 0.9906)
			(stroke
				(width 0.1)
				(type default)
			)
			(layer "B.Fab")
		)
		(fp_line
			(start -0.2794 -0.1016)
			(end 0.2794 -0.1016)
			(stroke
				(width 0.1)
				(type default)
			)
			(layer "B.Fab")
		)
		(fp_line
			(start 0.2794 0.9906)
			(end -0.2794 0.9906)
			(stroke
				(width 0.1)
				(type default)
			)
			(layer "B.Fab")
		)
		(fp_line
			(start -0.2794 0.9906)
			(end -0.2794 -0.1016)
			(stroke
				(width 0.1)
				(type default)
			)
			(layer "B.Fab")
		)
		(pad "1" smd rect
			(at 0 0 270)
			(size 0.508 0.508)
			(layers "B.Cu" "B.Mask" "B.Paste")
			(net "P3V3_STBY")
		)
		(pad "2" smd rect
			(at 0 0.889 270)
			(size 0.508 0.508)
			(layers "B.Cu" "B.Mask" "B.Paste")
			(net "RMII_BMC_OCP_TXD0_R")
		)
		(zone
			(layer "B.Cu")
			(hatch none 0.5)
			(connect_pads
				(clearance 0)
			)
			(min_thickness 0.25)
			(keepout
				(tracks allowed)
				(vias not_allowed)
				(pads allowed)
				(copperpour not_allowed)
				(footprints allowed)
			)
			(placement
				(enabled no)
				(sheetname "")
			)
			(fill
				(thermal_gap 0.5)
				(thermal_bridge_width 0.5)
				(island_removal_mode 0)
			)
			(polygon
				(pts
					(xy 401.853146 -35.823652) (xy 401.853146 -35.315652) (xy 402.234146 -35.315652) (xy 402.234146 -35.823652)
				)
			)
		)
		(zone
			(layer "B.Cu")
			(hatch none 0.5)
			(connect_pads
				(clearance 0)
			)
			(min_thickness 0.25)
			(keepout
				(tracks not_allowed)
				(vias allowed)
				(pads allowed)
				(copperpour not_allowed)
				(footprints allowed)
			)
			(placement
				(enabled no)
				(sheetname "")
			)
			(fill
				(thermal_gap 0.5)
				(thermal_bridge_width 0.5)
				(island_removal_mode 0)
			)
			(polygon
				(pts
					(xy 402.234146 -35.823652) (xy 402.234146 -35.315652) (xy 401.853146 -35.315652) (xy 401.853146 -35.823652)
				)
			)
		)
	)
	(footprint ""
		(layer "B.Cu")
		(at 248.8565 -135.4074 -90)
		(property "Reference" "C5M6"
			(at -1.848866 0.752348 270)
			(unlocked yes)
			(layer "B.SilkS")
			(effects
				(font
					(size 1.27 0.9652)
					(thickness 0.1524)
				)
				(justify mirror)
			)
		)
		(property "Value" ""
			(at 0 0 90)
			(layer "B.Fab")
			(effects
				(font
					(size 1.27 1.27)
				)
				(justify mirror)
			)
		)
		(duplicate_pad_numbers_are_jumpers no)
		(fp_rect
			(start 0.500126 1.598422)
			(end -0.500126 -0.201422)
			(stroke
				(width 0)
				(type default)
			)
			(fill no)
			(layer "B.CrtYd")
		)
		(fp_line
			(start -0.500126 1.598422)
			(end 0.500126 1.598422)
			(stroke
				(width 0.1)
				(type default)
			)
			(layer "B.Fab")
		)
		(fp_line
			(start 0.500126 1.598422)
			(end 0.500126 -0.201422)
			(stroke
				(width 0.1)
				(type default)
			)
			(layer "B.Fab")
		)
		(fp_line
			(start -0.500126 -0.201422)
			(end -0.500126 1.598422)
			(stroke
				(width 0.1)
				(type default)
			)
			(layer "B.Fab")
		)
		(fp_line
			(start 0.500126 -0.201422)
			(end -0.500126 -0.201422)
			(stroke
				(width 0.1)
				(type default)
			)
			(layer "B.Fab")
		)
		(pad "1" smd rect
			(at 0 0 180)
			(size 0.889 0.9906)
			(layers "B.Cu" "B.Mask" "B.Paste")
			(net "PVDDQ_DEF")
		)
		(pad "2" smd rect
			(at 0 1.397 180)
			(size 0.889 0.9906)
			(layers "B.Cu" "B.Mask" "B.Paste")
			(net "GND")
		)
		(zone
			(layer "B.Cu")
			(hatch none 0.5)
			(connect_pads
				(clearance 0)
			)
			(min_thickness 0.25)
			(keepout
				(tracks not_allowed)
				(vias allowed)
				(pads allowed)
				(copperpour not_allowed)
				(footprints allowed)
			)
			(placement
				(enabled no)
				(sheetname "")
			)
			(fill
				(thermal_gap 0.5)
				(thermal_bridge_width 0.5)
				(island_removal_mode 0)
			)
			(polygon
				(pts
					(xy 247.904 -134.9121) (xy 248.412 -134.9121) (xy 248.412 -135.9027) (xy 247.904 -135.9027)
				)
			)
		)
		(zone
			(layer "B.Cu")
			(hatch none 0.5)
			(connect_pads
				(clearance 0)
			)
			(min_thickness 0.25)
			(keepout
				(tracks allowed)
				(vias not_allowed)
				(pads allowed)
				(copperpour not_allowed)
				(footprints allowed)
			)
			(placement
				(enabled no)
				(sheetname "")
			)
			(fill
				(thermal_gap 0.5)
				(thermal_bridge_width 0.5)
				(island_removal_mode 0)
			)
			(polygon
				(pts
					(xy 247.904 -134.9121) (xy 248.412 -134.9121) (xy 248.412 -135.9027) (xy 247.904 -135.9027)
				)
			)
		)
	)
	(footprint ""
		(layer "B.Cu")
		(at 405.219408 -92.993718 -90)
		(property "Reference" "R2N17"
			(at 0 0 90)
			(layer "B.SilkS")
			(hide yes)
			(effects
				(font
					(size 1.27 1.27)
				)
				(justify mirror)
			)
		)
		(property "Value" ""
			(at 0 0 90)
			(layer "B.Fab")
			(effects
				(font
					(size 1.27 1.27)
				)
				(justify mirror)
			)
		)
		(duplicate_pad_numbers_are_jumpers no)
		(fp_poly
			(pts
				(xy 0.2794 -0.1016) (xy -0.2794 -0.1016) (xy -0.2794 0.9906) (xy 0.2794 0.9906)
			)
			(stroke
				(width 0)
				(type default)
			)
			(fill no)
			(layer "B.CrtYd")
		)
		(fp_line
			(start -0.2794 0.9906)
			(end -0.2794 -0.1016)
			(stroke
				(width 0.1)
				(type default)
			)
			(layer "B.Fab")
		)
		(fp_line
			(start 0.2794 0.9906)
			(end -0.2794 0.9906)
			(stroke
				(width 0.1)
				(type default)
			)
			(layer "B.Fab")
		)
		(fp_line
			(start -0.2794 -0.1016)
			(end 0.2794 -0.1016)
			(stroke
				(width 0.1)
				(type default)
			)
			(layer "B.Fab")
		)
		(fp_line
			(start 0.2794 -0.1016)
			(end 0.2794 0.9906)
			(stroke
				(width 0.1)
				(type default)
			)
			(layer "B.Fab")
		)
		(pad "1" smd rect
			(at 0 0 90)
			(size 0.508 0.508)
			(layers "B.Cu" "B.Mask" "B.Paste")
			(net "P3V3_STBY")
		)
		(pad "2" smd rect
			(at 0 0.889 90)
			(size 0.508 0.508)
			(layers "B.Cu" "B.Mask" "B.Paste")
			(net "FM_BOARD_SKU_ID4")
		)
		(zone
			(layer "B.Cu")
			(hatch none 0.5)
			(connect_pads
				(clearance 0)
			)
			(min_thickness 0.25)
			(keepout
				(tracks not_allowed)
				(vias allowed)
				(pads allowed)
				(copperpour not_allowed)
				(footprints allowed)
			)
			(placement
				(enabled no)
				(sheetname "")
			)
			(fill
				(thermal_gap 0.5)
				(thermal_bridge_width 0.5)
				(island_removal_mode 0)
			)
			(polygon
				(pts
					(xy 404.584408 -92.739718) (xy 404.584408 -93.247718) (xy 404.965408 -93.247718) (xy 404.965408 -92.739718)
				)
			)
		)
		(zone
			(layer "B.Cu")
			(hatch none 0.5)
			(connect_pads
				(clearance 0)
			)
			(min_thickness 0.25)
			(keepout
				(tracks allowed)
				(vias not_allowed)
				(pads allowed)
				(copperpour not_allowed)
				(footprints allowed)
			)
			(placement
				(enabled no)
				(sheetname "")
			)
			(fill
				(thermal_gap 0.5)
				(thermal_bridge_width 0.5)
				(island_removal_mode 0)
			)
			(polygon
				(pts
					(xy 404.965408 -92.739718) (xy 404.965408 -93.247718) (xy 404.584408 -93.247718) (xy 404.584408 -92.739718)
				)
			)
		)
	)
	(footprint ""
		(layer "B.Cu")
		(at 131.04622 -65.670938 -90)
		(property "Reference" "R7P28"
			(at 0 0 90)
			(layer "B.SilkS")
			(hide yes)
			(effects
				(font
					(size 1.27 1.27)
				)
				(justify mirror)
			)
		)
		(property "Value" ""
			(at 0 0 90)
			(layer "B.Fab")
			(effects
				(font
					(size 1.27 1.27)
				)
				(justify mirror)
			)
		)
		(duplicate_pad_numbers_are_jumpers no)
		(fp_poly
			(pts
				(xy 0.2794 -0.1016) (xy -0.2794 -0.1016) (xy -0.2794 0.9906) (xy 0.2794 0.9906)
			)
			(stroke
				(width 0)
				(type default)
			)
			(fill no)
			(layer "B.CrtYd")
		)
		(fp_line
			(start -0.2794 0.9906)
			(end -0.2794 -0.1016)
			(stroke
				(width 0.1)
				(type default)
			)
			(layer "B.Fab")
		)
		(fp_line
			(start 0.2794 0.9906)
			(end -0.2794 0.9906)
			(stroke
				(width 0.1)
				(type default)
			)
			(layer "B.Fab")
		)
		(fp_line
			(start -0.2794 -0.1016)
			(end 0.2794 -0.1016)
			(stroke
				(width 0.1)
				(type default)
			)
			(layer "B.Fab")
		)
		(fp_line
			(start 0.2794 -0.1016)
			(end 0.2794 0.9906)
			(stroke
				(width 0.1)
				(type default)
			)
			(layer "B.Fab")
		)
		(pad "1" smd rect
			(at 0 0 90)
			(size 0.508 0.508)
			(layers "B.Cu" "B.Mask" "B.Paste")
			(net "PVCCIO_CPU1")
		)
		(pad "2" smd rect
			(at 0 0.889 90)
			(size 0.508 0.508)
			(layers "B.Cu" "B.Mask" "B.Paste")
			(net "H_CPU1_PROCHOT_G_N")
		)
		(zone
			(layer "B.Cu")
			(hatch none 0.5)
			(connect_pads
				(clearance 0)
			)
			(min_thickness 0.25)
			(keepout
				(tracks not_allowed)
				(vias allowed)
				(pads allowed)
				(copperpour not_allowed)
				(footprints allowed)
			)
			(placement
				(enabled no)
				(sheetname "")
			)
			(fill
				(thermal_gap 0.5)
				(thermal_bridge_width 0.5)
				(island_removal_mode 0)
			)
			(polygon
				(pts
					(xy 130.41122 -65.416938) (xy 130.41122 -65.924938) (xy 130.79222 -65.924938) (xy 130.79222 -65.416938)
				)
			)
		)
		(zone
			(layer "B.Cu")
			(hatch none 0.5)
			(connect_pads
				(clearance 0)
			)
			(min_thickness 0.25)
			(keepout
				(tracks allowed)
				(vias not_allowed)
				(pads allowed)
				(copperpour not_allowed)
				(footprints allowed)
			)
			(placement
				(enabled no)
				(sheetname "")
			)
			(fill
				(thermal_gap 0.5)
				(thermal_bridge_width 0.5)
				(island_removal_mode 0)
			)
			(polygon
				(pts
					(xy 130.79222 -65.416938) (xy 130.79222 -65.924938) (xy 130.41122 -65.924938) (xy 130.41122 -65.416938)
				)
			)
		)
	)
	(footprint ""
		(layer "B.Cu")
		(at 402.606256 -29.603446 180)
		(property "Reference" "R25W120"
			(at -1.01473 0.656336 270)
			(unlocked yes)
			(layer "B.SilkS")
			(effects
				(font
					(size 0.4064 0.254)
					(thickness 0.1524)
				)
				(justify mirror)
			)
		)
		(property "Value" ""
			(at 0 0 0)
			(layer "B.Fab")
			(effects
				(font
					(size 1.27 1.27)
				)
				(justify mirror)
			)
		)
		(duplicate_pad_numbers_are_jumpers no)
		(fp_poly
			(pts
				(xy 0.4953 -0.2032) (xy -0.4953 -0.2032) (xy -0.4953 1.6002) (xy 0.4953 1.6002)
			)
			(stroke
				(width 0)
				(type default)
			)
			(fill no)
			(layer "B.CrtYd")
		)
		(fp_line
			(start 0.4953 1.6002)
			(end 0.4953 -0.2032)
			(stroke
				(width 0.1)
				(type default)
			)
			(layer "B.Fab")
		)
		(fp_line
			(start 0.4953 -0.2032)
			(end -0.4953 -0.2032)
			(stroke
				(width 0.1)
				(type default)
			)
			(layer "B.Fab")
		)
		(fp_line
			(start -0.4953 1.6002)
			(end 0.4953 1.6002)
			(stroke
				(width 0.1)
				(type default)
			)
			(layer "B.Fab")
		)
		(fp_line
			(start -0.4953 -0.2032)
			(end -0.4953 1.6002)
			(stroke
				(width 0.1)
				(type default)
			)
			(layer "B.Fab")
		)
		(pad "1" smd rect
			(at 0 0)
			(size 0.762 0.889)
			(layers "B.Cu" "B.Mask" "B.Paste")
			(net "P3V3_STBY")
		)
		(pad "2" smd rect
			(at 0 1.397)
			(size 0.762 0.889)
			(layers "B.Cu" "B.Mask" "B.Paste")
			(net "P3V3_USB2A_ALG")
		)
		(zone
			(layer "B.Cu")
			(hatch none 0.5)
			(connect_pads
				(clearance 0)
			)
			(min_thickness 0.25)
			(keepout
				(tracks not_allowed)
				(vias allowed)
				(pads allowed)
				(copperpour not_allowed)
				(footprints allowed)
			)
			(placement
				(enabled no)
				(sheetname "")
			)
			(fill
				(thermal_gap 0.5)
				(thermal_bridge_width 0.5)
				(island_removal_mode 0)
			)
			(polygon
				(pts
					(xy 402.225256 -30.555946) (xy 402.225256 -30.047946) (xy 402.987256 -30.047946) (xy 402.987256 -30.555946)
				)
			)
		)
		(zone
			(layer "B.Cu")
			(hatch none 0.5)
			(connect_pads
				(clearance 0)
			)
			(min_thickness 0.25)
			(keepout
				(tracks allowed)
				(vias not_allowed)
				(pads allowed)
				(copperpour not_allowed)
				(footprints allowed)
			)
			(placement
				(enabled no)
				(sheetname "")
			)
			(fill
				(thermal_gap 0.5)
				(thermal_bridge_width 0.5)
				(island_removal_mode 0)
			)
			(polygon
				(pts
					(xy 402.987256 -30.555946) (xy 402.987256 -30.047946) (xy 402.225256 -30.047946) (xy 402.225256 -30.555946)
				)
			)
		)
	)
	(footprint ""
		(layer "B.Cu")
		(at 367.968276 -156.15158 180)
		(property "Reference" "C22W27"
			(at 0 0 0)
			(layer "B.SilkS")
			(hide yes)
			(effects
				(font
					(size 1.27 1.27)
				)
				(justify mirror)
			)
		)
		(property "Value" "*"
			(at 0.0762 -6.2357 180)
			(unlocked yes)
			(layer "B.Fab")
			(hide yes)
			(effects
				(font
					(size 1.27 1.016)
					(thickness 0.1524)
				)
				(justify mirror)
			)
		)
		(property "Device Type" "SC22U16V5MX-4-GP_SMD-BCG5-SC22A"
			(at 0.0762 -8.2677 180)
			(unlocked yes)
			(layer "B.Fab")
			(hide yes)
			(effects
				(font
					(size 1.27 1.016)
					(thickness 0.1524)
				)
				(justify mirror)
			)
		)
		(duplicate_pad_numbers_are_jumpers no)
		(fp_line
			(start -0.635 0)
			(end 0.635 0)
			(stroke
				(width 0.508)
				(type default)
			)
			(layer "B.SilkS")
		)
		(fp_rect
			(start 0.9652 1.778)
			(end -0.9652 -1.778)
			(stroke
				(width 0)
				(type default)
			)
			(fill no)
			(layer "B.CrtYd")
		)
		(fp_poly
			(pts
				(xy 0.9652 -1.778) (xy -0.9652 -1.778) (xy -0.9652 1.778) (xy 0.9652 1.778)
			)
			(stroke
				(width 0)
				(type default)
			)
			(fill no)
			(layer "B.Fab")
		)
		(pad "1" smd rect
			(at 0 -0.9652)
			(size 1.397 1.143)
			(layers "B.Cu" "B.Mask" "B.Paste")
			(net "VR_FET_SW_P12V_STBY_PVDDQ_DEF")
		)
		(pad "2" smd rect
			(at 0 0.9652)
			(size 1.397 1.143)
			(layers "B.Cu" "B.Mask" "B.Paste")
			(net "GND")
		)
	)
)
